FILE_TYPE = CONNECTIVITY;
{Allegro Design Entry HDL 17.2-2016 S081 (4005846) 1/11/2022}
"PAGE_NUMBER" = 244;
0"NC";
1"P12V_AUX\g";
2"P5V_AUX_VCC\g";
3"P5V_AUX_VCC\G";
4"P5V_AUX\g";
5"GND\g";
6"GND\g";
7"GND\g";
8"GND\g";
9"GND\g";
10"GND\g";
11"GND\g";
12"GND\g";
13"GND\g";
14"GND\g";
15"SW_P5V_AUX_BST";
16"SW_P5V_AUX_SW";
17"P5V_AUX_FB";
18"SW_P5V_AUX_FLT";
19"PWRGD_P5V_AUX";
20"PWRGD_P5V_AUX_R";
21"P5V_AUX_REF";
22"P5V_AUX_CS";
23"PWRGD_P3V3_AUX";
24"P5V_AUX_MODE";
%"GND"
"1","(-7750,6525)","0","logical_power","I1";
;
HDL_POWER"GND"
SIZE"1B"
CDS_LIB"logical_power";
"A<SIZE-1..0>\NAC"5;
%"Q_RES"
"1","(-5550,5900)","0","pure_quanta","I10";
;
PART_NUMBER"CS00002JB13"
TOLERANCE"5%"
VALUE"0"
MATERIAL"CHIP"
WATTAGE"1/16W"
PACK_TYPE"0402LF"
LOCATION"PR3337"
CDS_LIB"pure_quanta"
$SEC"1"
CDS_SEC"1";
"B"
$PN"2"11;
"A"
$PN"1"24;
%"Q_CAP"
"1","(-6575,6750)","0","pure_quanta","I11";
;
PART_NUMBER"CH6223MEA01"
MATERIAL"X6S"
PACK_TYPE"C0805"
VOLTAGE"16V"
TOLERANCE"20%"
VALUE"22UF"
LOCATION"PC1850"
CDS_LIB"pure_quanta"
$SEC"1"
CDS_SEC"1";
"B"
$PN"2"7;
"A"
$PN"1"18;
%"Q_CAP"
"1","(-6125,6750)","0","pure_quanta","I12";
;
PART_NUMBER"CH6223MEA01"
VALUE"22UF"
PACK_TYPE"C0805"
VOLTAGE"16V"
TOLERANCE"20%"
MATERIAL"X6S"
LOCATION"PC1898"
CDS_LIB"pure_quanta"
$SEC"1"
CDS_SEC"1";
"B"
$PN"2"7;
"A"
$PN"1"18;
%"Q_CAP"
"1","(-5725,6750)","0","pure_quanta","I14";
;
PART_NUMBER"CH5103KEB01"
MATERIAL"X6S"
TOLERANCE"10%"
PACK_TYPE"C0402"
VOLTAGE"16V"
VALUE"1UF"
LOCATION"PC1846"
CDS_LIB"pure_quanta"
$SEC"1"
CDS_SEC"1";
"B"
$PN"2"7;
"A"
$PN"1"18;
%"GND"
"1","(-5462,4893)","0","logical_power","I15";
;
HDL_POWER"GND"
SIZE"1B"
CDS_LIB"logical_power";
"A<SIZE-1..0>\NAC"8;
%"Q_RES"
"2","(-5462,5182)","0","pure_quanta","I16";
;
PART_NUMBER"CS31692FB03"
PACK_TYPE"0402LF"
WATTAGE"1/16W"
MATERIAL"CHIP"
VALUE"16.9K"
TOLERANCE"1%"
LOCATION"PR89"
SEC_TYPE"0402LF"
CDS_LIB"pure_quanta"
SEC"1";
"A"
$PN"1"22;
"B"
$PN"2"8;
%"GND"
"1","(-3950,5075)","0","logical_power","I17";
;
HDL_POWER"GND"
SIZE"1B"
CDS_LIB"logical_power";
"A<SIZE-1..0>\NAC"9;
%"GND"
"1","(-3825,5075)","0","logical_power","I18";
;
HDL_POWER"GND"
SIZE"1B"
CDS_LIB"logical_power";
"A<SIZE-1..0>\NAC"10;
%"GND"
"1","(-5150,5825)","0","logical_power","I19";
;
HDL_POWER"GND"
CDS_LIB"logical_power"
SIZE"1B";
"A<SIZE-1..0>\NAC"11;
%"Q_CAP"
"1","(-7750,6775)","0","pure_quanta","I2";
;
PART_NUMBER"CH4106K1B01"
MATERIAL"X7R"
TOLERANCE"10%"
VOLTAGE"50V"
PACK_TYPE"C0402"
VALUE"100NF"
LOCATION"PC1648"
CDS_LIB"pure_quanta"
$SEC"1"
CDS_SEC"1";
"B"
$PN"2"5;
"A"
$PN"1"1;
%"RS53318LR"
"1","(-4575,6025)","0","pure_quanta","I20";
;
PART_NUMBER"AL053318002"
MATERIAL"IC"
VALUE"RS53318LR"
PART_TYPE"SMLF"
LOCATION"PU181"
SEC_TYPE""
CDS_LIB"pure_quanta"
NEEDS_NO_SIZE"TRUE"
CDS_LMAN_SYM_OUTLINE"-250,725,250,-725"
SEC"1";
"VIN2"
$PN"21"18;
"CS"
$PN"3"22;
"MODE"
$PN"4"24;
"REF"
$PN"5"21;
"SW"
$PN"20"16;
"RTN"
$PN"6"12;
"VCC"
$PN"19"2;
"AGND"
$PN"2"9;
"FB"
$PN"7"17;
"BST"
$PN"1"15;
"EN"
$PN"8"23;
"PGND"
$PN"11_18"9;
"PGOOD"
$PN"9"20;
"VIN1"
$PN"10"18;
%"Q_CAP"
"1","(-3825,5300)","0","pure_quanta","I21";
;
PART_NUMBER"CH4104K1B00"
TOLERANCE"10%"
VOLTAGE"25V"
VALUE"0.1UF"
MATERIAL"X7R"
PACK_TYPE"0402"
LOCATION"PC1853"
CDS_LIB"pure_quanta"
$SEC"1"
CDS_SEC"1";
"B"
$PN"2"10;
"A"
$PN"1"21;
%"Q_CAP"
"2","(-1900,5075)","0","pure_quanta","I22";
;
PART_NUMBER"TMP_QCH04706JB01"
PACK_TYPE"0402"
MATERIAL"NPO"
TOLERANCE"5%"
VOLTAGE"50V"
VALUE"47PF"
LOCATION"PC1877"
CDS_LIB"pure_quanta"
$SEC"1"
CDS_SEC"1";
"A"
$PN"1"17;
"B"
$PN"2"4;
%"GND"
"1","(-3400,5150)","0","logical_power","I23";
;
HDL_POWER"GND"
SIZE"1B"
CDS_LIB"logical_power";
"A<SIZE-1..0>\NAC"12;
%"GND"
"1","(-3250,5150)","0","logical_power","I24";
;
HDL_POWER"GND"
SIZE"1B"
CDS_LIB"logical_power";
"A<SIZE-1..0>\NAC"13;
%"Q_RES"
"2","(-3250,5475)","0","pure_quanta","I25";
;
PART_NUMBER"CS31182BB06"
MATERIAL"CHIP"
PACK_TYPE"0402LF"
VALUE"11.8K"
WATTAGE"1/16W"
TOLERANCE"0.1%"
LOCATION"PR91"
CDS_LIB"pure_quanta"
$SEC"1"
CDS_SEC"1";
"A"
$PN"1"17;
"B"
$PN"2"13;
%"Q_CAP"
"1","(-3300,6350)","0","pure_quanta","I26";
;
PART_NUMBER"CH4224K1B01"
VALUE"0.22UF"
MATERIAL"X7R"
PACK_TYPE"C0402"
VOLTAGE"25V"
TOLERANCE"10%"
LOCATION"PC1847"
CDS_LIB"pure_quanta"
$SEC"1"
CDS_SEC"1";
"B"
$PN"2"16;
"A"
$PN"1"15;
%"Q_RES"
"2","(-3300,7075)","0","pure_quanta","I27";
;
PART_NUMBER"CS31002FB08"
MATERIAL"CHIP"
TOLERANCE"1%"
WATTAGE"1/16W"
VALUE"10K"
PACK_TYPE"0402LF"
LOCATION"R2356"
CDS_LIB"pure_quanta"
SEC_TYPE"0402LF"
SEC"1";
"A"
$PN"1"3;
"B"
$PN"2"20;
%"Q_RES"
"1","(-2725,6700)","0","pure_quanta","I28";
;
PART_NUMBER"CS00002JB13"
VALUE"0"
WATTAGE"1/16W"
MATERIAL"CHIP"
TOLERANCE"5%"
PACK_TYPE"0402LF"
LOCATION"R2316"
CDS_LIB"pure_quanta"
$SEC"1"
CDS_SEC"1";
"B"
$PN"2"19;
"A"
$PN"1"20;
%"P1V0_AUX"
"1","(-7746,7195)","0","logical_power","I3";
;
HDL_POWER"P12V_AUX"
ROOM"VR_DDR1_POWER_STAGE"
CDS_LIB"logical_power";
"A"1;
%"Q_INDUCTOR"
"1","(-2400,6225)","0","pure_quanta","I30";
;
PART_NUMBER"CV-47A0MZ10"
MATERIAL"IND"
VALUE"4.7UH"
PACK_TYPE"SMLF"
LOCATION"PL65"
CDS_LIB"pure_quanta"
NEEDS_NO_SIZE"TRUE"
$SEC"1"
CDS_SEC"1";
"1"
$PN"1"16;
"2"
$PN"2"4;
%"Q_CAPP"
"1","(-1125,5950)","0","pure_quanta","I32";
;
PART_NUMBER"CC72201MZ28"
VOLTAGE"6.3V"
TOLERANCE"20%"
VALUE"220UF"
PACK_TYPE"SMLF"
MATERIAL"ALUM"
LOCATION"PC1845"
CDS_LIB"pure_quanta"
$SEC"1"
CDS_SEC"1";
"A"
$PN"1"4;
"B"
$PN"2"14;
%"Q_CAP"
"1","(-675,5950)","0","pure_quanta","I33";
;
PART_NUMBER"CH6222MEA01"
MATERIAL"X6S"
VOLTAGE"10V"
TOLERANCE"20%"
PACK_TYPE"C0805"
VALUE"22UF"
LOCATION"PC1855"
CDS_LIB"pure_quanta"
$SEC"1"
CDS_SEC"1";
"B"
$PN"2"14;
"A"
$PN"1"4;
%"Q_CAP"
"1","(-175,5950)","0","pure_quanta","I34";
;
PART_NUMBER"CH6222MEA01"
TOLERANCE"20%"
VOLTAGE"10V"
VALUE"22UF"
PACK_TYPE"C0805"
MATERIAL"X6S"
LOCATION"PC1856"
CDS_LIB"pure_quanta"
$SEC"1"
CDS_SEC"1";
"B"
$PN"2"14;
"A"
$PN"1"4;
%"GND"
"1","(250,5550)","0","logical_power","I35";
;
HDL_POWER"GND"
SIZE"1B"
CDS_LIB"logical_power";
"A<SIZE-1..0>\NAC"14;
%"Q_CAP"
"1","(250,5950)","0","pure_quanta","I36";
;
PART_NUMBER"CH4104K1B00"
VOLTAGE"25V"
VALUE"0.1UF"
TOLERANCE"10%"
MATERIAL"X7R"
PACK_TYPE"0402"
LOCATION"PC1852"
SEC_TYPE"0402"
CDS_LIB"pure_quanta"
SEC"1";
"B"
$PN"2"14;
"A"
$PN"1"4;
%"UNIVERSAL_POWER"
"1","(-3300,7375)","0","logical_power","I37";
;
HDL_POWER"P5V_AUX_VCC"
CDS_LIB"logical_power";
"A"3;
%"P1V0"
"1","(750,6675)","0","logical_power","I38";
;
HDL_POWER"P5V_AUX"
CDS_LIB"logical_power";
"A"4;
%"Q_RES"
"1","(-1875,5400)","0","pure_quanta","I39";
;
PART_NUMBER"CS38872FB18"
VALUE"88.7K"
MATERIAL"CHIP"
TOLERANCE"1%"
PACK_TYPE"0402LF"
LOCATION"PR92"
WATTAGE"1/16W"
CDS_LIB"pure_quanta"
$SEC"1"
CDS_SEC"1";
"B"
$PN"2"4;
"A"
$PN"1"17;
%"GND"
"1","(-6400,5100)","0","logical_power","I4";
;
HDL_POWER"GND"
CDS_LIB"logical_power"
SIZE"1B";
"A<SIZE-1..0>\NAC"6;
%"Q_INDUCTOR"
"1","(-7475,7000)","0","pure_quanta","I5";
;
PART_NUMBER"CX220TN1001"
PACK_TYPE"SMLF"
MATERIAL"IND"
VALUE"BLM18SN220TN1D/8000MA"
LOCATION"PL64"
CDS_LIB"pure_quanta"
NEEDS_NO_SIZE"TRUE"
$SEC"1"
CDS_SEC"1";
"1"
$PN"1"1;
"2"
$PN"2"18;
%"GND"
"1","(-6975,6375)","0","logical_power","I6";
;
HDL_POWER"GND"
SIZE"1B"
CDS_LIB"logical_power";
"A<SIZE-1..0>\NAC"7;
%"Q_CAP"
"1","(-6975,6750)","0","pure_quanta","I7";
;
PART_NUMBER"CH6223MEA01"
VOLTAGE"16V"
TOLERANCE"20%"
PACK_TYPE"C0805"
MATERIAL"X6S"
VALUE"22UF"
LOCATION"PC1849"
CDS_LIB"pure_quanta"
$SEC"1"
CDS_SEC"1";
"B"
$PN"2"7;
"A"
$PN"1"18;
%"Q_CAP"
"1","(-6400,5475)","2","pure_quanta","I8";
;
PART_NUMBER"CH5104KEB02"
PACK_TYPE"C0402"
VALUE"1UF"
TOLERANCE"10%"
MATERIAL"X6S"
VOLTAGE"25V"
LOCATION"PC1848"
CDS_LIB"pure_quanta"
SIGNAL_MODEL"DEFAULT_CAPACITOR_100000PF_2_1"
SEC_TYPE"C0402"
SEC"1";
"B"
$PN"2"6;
"A"
$PN"1"2;
%"UNIVERSAL_POWER"
"1","(-6400,5975)","0","logical_power","I9";
;
HDL_POWER"P5V_AUX_VCC"
CDS_LIB"logical_power";
"A"2;
END.
